(kicad_pcb
	(version 20260206)
	(generator "pcbnew")
	(generator_version "10.0")
	(general
		(thickness 1.6)
		(legacy_teardrops no)
	)
	(paper "A4")
	(title_block
		(title "Wiwynn_Tioga_Pass_MB.brd")
		(comment 1 "Tioga Pass / footprints 2954-2960 of 4770")
	)
	(layers
		(0 "F.Cu" signal "TOP")
		(4 "In1.Cu" signal "L2GND")
		(6 "In2.Cu" signal "L3")
		(8 "In3.Cu" signal "L4GND")
		(10 "In4.Cu" signal "L5")
		(12 "In5.Cu" signal "L6GND")
		(14 "In6.Cu" signal "L7VCC")
		(16 "In7.Cu" signal "L8VCC")
		(18 "In8.Cu" signal "L9GND")
		(20 "In9.Cu" signal "L10")
		(22 "In10.Cu" signal "L11GND")
		(24 "In11.Cu" signal "L12")
		(26 "In12.Cu" signal "L13GND")
		(2 "B.Cu" signal "BOTTOM")
		(9 "F.Adhes" user "F.Adhesive")
		(11 "B.Adhes" user "B.Adhesive")
		(13 "F.Paste" user "Package Geometry/Pastemask Top")
		(15 "B.Paste" user "Package Geometry/Pastemask Bottom")
		(5 "F.SilkS" user "Ref Des/Silkscreen Top")
		(7 "B.SilkS" user "Ref Des/Silkscreen Bottom")
		(1 "F.Mask" user "Board Geometry/Soldermask Top")
		(3 "B.Mask" user "Board Geometry/Soldermask Bottom")
		(17 "Dwgs.User" user "User.Drawings")
		(19 "Cmts.User" user "User.Comments")
		(21 "Eco1.User" user "User.Eco1")
		(23 "Eco2.User" user "User.Eco2")
		(25 "Edge.Cuts" user "Board Geometry/Outline")
		(27 "Margin" user)
		(31 "F.CrtYd" user "Package Geometry/Place Bound Top")
		(29 "B.CrtYd" user "Package Geometry/Place Bound Bottom")
		(35 "F.Fab" user "Ref Des/Assembly Top")
		(33 "B.Fab" user "Ref Des/Assembly Bottom")
	)
	(footprint ""
		(layer "B.Cu")
		(at 30.452568 -144.977612 90)
		(property "Reference" "C9L7"
			(at 0 0 90)
			(layer "B.SilkS")
			(hide yes)
			(effects
				(font
					(size 1.27 1.27)
				)
				(justify mirror)
			)
		)
		(property "Value" ""
			(at 0 0 90)
			(layer "B.Fab")
			(effects
				(font
					(size 1.27 1.27)
				)
				(justify mirror)
			)
		)
		(duplicate_pad_numbers_are_jumpers no)
		(fp_poly
			(pts
				(xy -0.3048 -0.1016) (xy -0.3048 0.9906) (xy 0.3048 0.9906) (xy 0.3048 -0.1016)
			)
			(stroke
				(width 0)
				(type default)
			)
			(fill no)
			(layer "B.CrtYd")
		)
		(fp_line
			(start 0.3048 -0.1016)
			(end 0.3048 0.9906)
			(stroke
				(width 0.1)
				(type default)
			)
			(layer "B.Fab")
		)
		(fp_line
			(start -0.3048 -0.1016)
			(end 0.3048 -0.1016)
			(stroke
				(width 0.1)
				(type default)
			)
			(layer "B.Fab")
		)
		(fp_line
			(start 0.3048 0.9906)
			(end -0.3048 0.9906)
			(stroke
				(width 0.1)
				(type default)
			)
			(layer "B.Fab")
		)
		(fp_line
			(start -0.3048 0.9906)
			(end -0.3048 -0.1016)
			(stroke
				(width 0.1)
				(type default)
			)
			(layer "B.Fab")
		)
		(pad "1" smd rect
			(at 0 0 270)
			(size 0.508 0.508)
			(layers "B.Cu" "B.Mask" "B.Paste")
			(net "M_L_VREF")
		)
		(pad "2" smd rect
			(at 0 0.889 270)
			(size 0.508 0.508)
			(layers "B.Cu" "B.Mask" "B.Paste")
			(net "GND")
		)
		(zone
			(layer "B.Cu")
			(hatch none 0.5)
			(connect_pads
				(clearance 0)
			)
			(min_thickness 0.25)
			(keepout
				(tracks allowed)
				(vias not_allowed)
				(pads allowed)
				(copperpour not_allowed)
				(footprints allowed)
			)
			(placement
				(enabled no)
				(sheetname "")
			)
			(fill
				(thermal_gap 0.5)
				(thermal_bridge_width 0.5)
				(island_removal_mode 0)
			)
			(polygon
				(pts
					(xy 30.706568 -145.231612) (xy 30.706568 -144.723612) (xy 31.087568 -144.723612) (xy 31.087568 -145.231612)
				)
			)
		)
		(zone
			(layer "B.Cu")
			(hatch none 0.5)
			(connect_pads
				(clearance 0)
			)
			(min_thickness 0.25)
			(keepout
				(tracks not_allowed)
				(vias allowed)
				(pads allowed)
				(copperpour not_allowed)
				(footprints allowed)
			)
			(placement
				(enabled no)
				(sheetname "")
			)
			(fill
				(thermal_gap 0.5)
				(thermal_bridge_width 0.5)
				(island_removal_mode 0)
			)
			(polygon
				(pts
					(xy 31.087568 -145.231612) (xy 31.087568 -144.723612) (xy 30.706568 -144.723612) (xy 30.706568 -145.231612)
				)
			)
		)
	)
	(footprint ""
		(layer "B.Cu")
		(at 389.1915 -61.341 -90)
		(property "Reference" "R2T11"
			(at 0 0 90)
			(layer "B.SilkS")
			(hide yes)
			(effects
				(font
					(size 1.27 1.27)
				)
				(justify mirror)
			)
		)
		(property "Value" ""
			(at 0 0 90)
			(layer "B.Fab")
			(effects
				(font
					(size 1.27 1.27)
				)
				(justify mirror)
			)
		)
		(duplicate_pad_numbers_are_jumpers no)
		(fp_poly
			(pts
				(xy 0.2794 -0.1016) (xy -0.2794 -0.1016) (xy -0.2794 0.9906) (xy 0.2794 0.9906)
			)
			(stroke
				(width 0)
				(type default)
			)
			(fill no)
			(layer "B.CrtYd")
		)
		(fp_line
			(start -0.2794 0.9906)
			(end -0.2794 -0.1016)
			(stroke
				(width 0.1)
				(type default)
			)
			(layer "B.Fab")
		)
		(fp_line
			(start 0.2794 0.9906)
			(end -0.2794 0.9906)
			(stroke
				(width 0.1)
				(type default)
			)
			(layer "B.Fab")
		)
		(fp_line
			(start -0.2794 -0.1016)
			(end 0.2794 -0.1016)
			(stroke
				(width 0.1)
				(type default)
			)
			(layer "B.Fab")
		)
		(fp_line
			(start 0.2794 -0.1016)
			(end 0.2794 0.9906)
			(stroke
				(width 0.1)
				(type default)
			)
			(layer "B.Fab")
		)
		(pad "1" smd rect
			(at 0 0 90)
			(size 0.508 0.508)
			(layers "B.Cu" "B.Mask" "B.Paste")
			(net "P3V3_STBY")
		)
		(pad "2" smd rect
			(at 0 0.889 90)
			(size 0.508 0.508)
			(layers "B.Cu" "B.Mask" "B.Paste")
			(net "FM_DUAL_BIOS_SEL_N")
		)
		(zone
			(layer "B.Cu")
			(hatch none 0.5)
			(connect_pads
				(clearance 0)
			)
			(min_thickness 0.25)
			(keepout
				(tracks not_allowed)
				(vias allowed)
				(pads allowed)
				(copperpour not_allowed)
				(footprints allowed)
			)
			(placement
				(enabled no)
				(sheetname "")
			)
			(fill
				(thermal_gap 0.5)
				(thermal_bridge_width 0.5)
				(island_removal_mode 0)
			)
			(polygon
				(pts
					(xy 388.5565 -61.087) (xy 388.5565 -61.595) (xy 388.9375 -61.595) (xy 388.9375 -61.087)
				)
			)
		)
		(zone
			(layer "B.Cu")
			(hatch none 0.5)
			(connect_pads
				(clearance 0)
			)
			(min_thickness 0.25)
			(keepout
				(tracks allowed)
				(vias not_allowed)
				(pads allowed)
				(copperpour not_allowed)
				(footprints allowed)
			)
			(placement
				(enabled no)
				(sheetname "")
			)
			(fill
				(thermal_gap 0.5)
				(thermal_bridge_width 0.5)
				(island_removal_mode 0)
			)
			(polygon
				(pts
					(xy 388.9375 -61.087) (xy 388.9375 -61.595) (xy 388.5565 -61.595) (xy 388.5565 -61.087)
				)
			)
		)
	)
	(footprint ""
		(layer "B.Cu")
		(at 336.042 -99.314 90)
		(property "Reference" "C3N35"
			(at 1.62433 -3.81 0)
			(unlocked yes)
			(layer "B.SilkS")
			(effects
				(font
					(size 0.7874 0.5842)
					(thickness 0.1524)
				)
				(justify mirror)
			)
		)
		(property "Value" ""
			(at 0 0 90)
			(layer "B.Fab")
			(effects
				(font
					(size 1.27 1.27)
				)
				(justify mirror)
			)
		)
		(duplicate_pad_numbers_are_jumpers no)
		(fp_line
			(start 2.563114 -1.616456)
			(end 2.563114 1.633728)
			(stroke
				(width 0.1524)
				(type default)
			)
			(layer "B.SilkS")
		)
		(fp_line
			(start 1.6002 -1.616456)
			(end 2.563114 -1.616456)
			(stroke
				(width 0.1524)
				(type default)
			)
			(layer "B.SilkS")
		)
		(fp_line
			(start -1.6002 -1.616456)
			(end -2.504948 -1.616456)
			(stroke
				(width 0.1524)
				(type default)
			)
			(layer "B.SilkS")
		)
		(fp_line
			(start -2.504948 -1.616456)
			(end -2.504948 1.633728)
			(stroke
				(width 0.1524)
				(type default)
			)
			(layer "B.SilkS")
		)
		(fp_line
			(start 2.563114 1.633728)
			(end 1.6002 1.633728)
			(stroke
				(width 0.1524)
				(type default)
			)
			(layer "B.SilkS")
		)
		(fp_line
			(start -2.504948 1.633728)
			(end -1.6002 1.633728)
			(stroke
				(width 0.1524)
				(type default)
			)
			(layer "B.SilkS")
		)
		(fp_line
			(start 2.286 7.366)
			(end 2.286 1.632712)
			(stroke
				(width 0.1524)
				(type default)
			)
			(layer "B.SilkS")
		)
		(fp_line
			(start 2.286 7.366)
			(end 1.60147 7.366)
			(stroke
				(width 0.1524)
				(type default)
			)
			(layer "B.SilkS")
		)
		(fp_line
			(start -2.286 7.366)
			(end -2.286 1.63195)
			(stroke
				(width 0.1524)
				(type default)
			)
			(layer "B.SilkS")
		)
		(fp_line
			(start -2.286 7.366)
			(end -1.600708 7.366)
			(stroke
				(width 0.1524)
				(type default)
			)
			(layer "B.SilkS")
		)
		(fp_rect
			(start 2.286 7.366)
			(end -2.286 -0.254)
			(stroke
				(width 0)
				(type default)
			)
			(fill no)
			(layer "B.CrtYd")
		)
		(fp_line
			(start 2.286 -0.254)
			(end -2.286 -0.254)
			(stroke
				(width 0.1)
				(type default)
			)
			(layer "B.Fab")
		)
		(fp_line
			(start -2.286 -0.254)
			(end -2.286 7.366)
			(stroke
				(width 0.1)
				(type default)
			)
			(layer "B.Fab")
		)
		(fp_line
			(start 2.286 7.366)
			(end 2.286 -0.254)
			(stroke
				(width 0.1)
				(type default)
			)
			(layer "B.Fab")
		)
		(fp_line
			(start -2.286 7.366)
			(end 2.286 7.366)
			(stroke
				(width 0.1)
				(type default)
			)
			(layer "B.Fab")
		)
		(pad "1" smd rect
			(at 0 0 270)
			(size 2.54 3.048)
			(layers "B.Cu" "B.Mask" "B.Paste")
			(net "PVCCIO_CPU0")
		)
		(pad "2" smd rect
			(at 0 7.112 270)
			(size 2.54 3.048)
			(layers "B.Cu" "B.Mask" "B.Paste")
			(net "GND")
		)
	)
	(footprint ""
		(layer "B.Cu")
		(at 273.560286 -79.60614 180)
		(property "Reference" "C5P11"
			(at 0 0 0)
			(layer "B.SilkS")
			(hide yes)
			(effects
				(font
					(size 1.27 1.27)
				)
				(justify mirror)
			)
		)
		(property "Value" ""
			(at 0 0 0)
			(layer "B.Fab")
			(effects
				(font
					(size 1.27 1.27)
				)
				(justify mirror)
			)
		)
		(duplicate_pad_numbers_are_jumpers no)
		(fp_poly
			(pts
				(xy 0.7239 -0.2159) (xy -0.7239 -0.2159) (xy -0.7239 1.9939) (xy 0.7239 1.9939)
			)
			(stroke
				(width 0)
				(type default)
			)
			(fill no)
			(layer "B.CrtYd")
		)
		(fp_line
			(start 0.7239 1.9939)
			(end -0.7239 1.9939)
			(stroke
				(width 0.1)
				(type default)
			)
			(layer "B.Fab")
		)
		(fp_line
			(start 0.7239 -0.2159)
			(end 0.7239 1.9939)
			(stroke
				(width 0.1)
				(type default)
			)
			(layer "B.Fab")
		)
		(fp_line
			(start -0.7239 1.9939)
			(end -0.7239 -0.2159)
			(stroke
				(width 0.1)
				(type default)
			)
			(layer "B.Fab")
		)
		(fp_line
			(start -0.7239 -0.2159)
			(end 0.7239 -0.2159)
			(stroke
				(width 0.1)
				(type default)
			)
			(layer "B.Fab")
		)
		(pad "1" smd rect
			(at 0 0)
			(size 1.27 1.016)
			(layers "B.Cu" "B.Mask" "B.Paste")
			(net "PVCCMCP_CPU0")
		)
		(pad "2" smd rect
			(at 0 1.778)
			(size 1.27 1.016)
			(layers "B.Cu" "B.Mask" "B.Paste")
			(net "GND")
		)
		(zone
			(layer "B.Cu")
			(hatch none 0.5)
			(connect_pads
				(clearance 0)
			)
			(min_thickness 0.25)
			(keepout
				(tracks not_allowed)
				(vias allowed)
				(pads allowed)
				(copperpour not_allowed)
				(footprints allowed)
			)
			(placement
				(enabled no)
				(sheetname "")
			)
			(fill
				(thermal_gap 0.5)
				(thermal_bridge_width 0.5)
				(island_removal_mode 0)
			)
			(polygon
				(pts
					(xy 272.925286 -80.11414) (xy 274.195286 -80.11414) (xy 274.195286 -80.87614) (xy 272.925286 -80.87614)
				)
			)
		)
	)
	(footprint ""
		(layer "B.Cu")
		(at 214.503 -63.11392)
		(property "Reference" "C6R2"
			(at 0 0 0)
			(layer "B.SilkS")
			(hide yes)
			(effects
				(font
					(size 1.27 1.27)
				)
				(justify mirror)
			)
		)
		(property "Value" ""
			(at 0 0 0)
			(layer "B.Fab")
			(effects
				(font
					(size 1.27 1.27)
				)
				(justify mirror)
			)
		)
		(duplicate_pad_numbers_are_jumpers no)
		(fp_poly
			(pts
				(xy 0.4953 -0.2032) (xy -0.4953 -0.2032) (xy -0.4953 1.6002) (xy 0.4953 1.6002)
			)
			(stroke
				(width 0)
				(type default)
			)
			(fill no)
			(layer "B.CrtYd")
		)
		(fp_line
			(start -0.4953 -0.2032)
			(end -0.4953 1.6002)
			(stroke
				(width 0.1)
				(type default)
			)
			(layer "B.Fab")
		)
		(fp_line
			(start -0.4953 1.6002)
			(end 0.4953 1.6002)
			(stroke
				(width 0.1)
				(type default)
			)
			(layer "B.Fab")
		)
		(fp_line
			(start 0.4953 -0.2032)
			(end -0.4953 -0.2032)
			(stroke
				(width 0.1)
				(type default)
			)
			(layer "B.Fab")
		)
		(fp_line
			(start 0.4953 1.6002)
			(end 0.4953 -0.2032)
			(stroke
				(width 0.1)
				(type default)
			)
			(layer "B.Fab")
		)
		(pad "1" smd rect
			(at 0 0 180)
			(size 0.762 0.889)
			(layers "B.Cu" "B.Mask" "B.Paste")
			(net "PVCCIN_CPU0")
		)
		(pad "2" smd rect
			(at 0 1.397 180)
			(size 0.762 0.889)
			(layers "B.Cu" "B.Mask" "B.Paste")
			(net "GND")
		)
		(zone
			(layer "B.Cu")
			(hatch none 0.5)
			(connect_pads
				(clearance 0)
			)
			(min_thickness 0.25)
			(keepout
				(tracks not_allowed)
				(vias allowed)
				(pads allowed)
				(copperpour not_allowed)
				(footprints allowed)
			)
			(placement
				(enabled no)
				(sheetname "")
			)
			(fill
				(thermal_gap 0.5)
				(thermal_bridge_width 0.5)
				(island_removal_mode 0)
			)
			(polygon
				(pts
					(xy 214.884 -62.66942) (xy 214.122 -62.66942) (xy 214.122 -62.16142) (xy 214.884 -62.16142)
				)
			)
		)
	)
	(footprint ""
		(layer "B.Cu")
		(at 375.544842 -77.894434)
		(property "Reference" "C2P2"
			(at 0 0 0)
			(layer "B.SilkS")
			(hide yes)
			(effects
				(font
					(size 1.27 1.27)
				)
				(justify mirror)
			)
		)
		(property "Value" ""
			(at 0 0 0)
			(layer "B.Fab")
			(effects
				(font
					(size 1.27 1.27)
				)
				(justify mirror)
			)
		)
		(duplicate_pad_numbers_are_jumpers no)
		(fp_rect
			(start 0.2794 0.9144)
			(end -0.2794 -0.1143)
			(stroke
				(width 0)
				(type default)
			)
			(fill no)
			(layer "B.CrtYd")
		)
		(fp_line
			(start -0.2794 -0.1143)
			(end -0.2794 0.9144)
			(stroke
				(width 0.1)
				(type default)
			)
			(layer "B.Fab")
		)
		(fp_line
			(start -0.2794 0.9144)
			(end 0.2794 0.9144)
			(stroke
				(width 0.1)
				(type default)
			)
			(layer "B.Fab")
		)
		(fp_line
			(start 0.2794 -0.1143)
			(end -0.2794 -0.1143)
			(stroke
				(width 0.1)
				(type default)
			)
			(layer "B.Fab")
		)
		(fp_line
			(start 0.2794 0.9144)
			(end 0.2794 -0.1143)
			(stroke
				(width 0.1)
				(type default)
			)
			(layer "B.Fab")
		)
		(pad "1" smd custom
			(at 0 0 270)
			(size 0.10414 0.10414)
			(layers "B.Cu" "B.Mask" "B.Paste")
			(net "P3V3_STBY")
			(options
				(clearance outline)
				(anchor circle)
			)
			(primitives
				(gr_poly
					(pts
						(xy -0.20828 -0.08636) (xy -0.20828 0.08636) (xy -0.08636 0.20828) (xy 0.086614 0.20828) (xy 0.20828 0.086614)
						(xy 0.20828 -0.08636) (xy 0.08636 -0.20828) (xy -0.08636 -0.20828)
					)
					(width 0)
					(fill yes)
				)
			)
		)
		(pad "2" smd custom
			(at 0 0.8001 270)
			(size 0.10414 0.10414)
			(layers "B.Cu" "B.Mask" "B.Paste")
			(net "GND")
			(options
				(clearance outline)
				(anchor circle)
			)
			(primitives
				(gr_poly
					(pts
						(xy -0.20828 -0.08636) (xy -0.20828 0.08636) (xy -0.08636 0.20828) (xy 0.086614 0.20828) (xy 0.20828 0.086614)
						(xy 0.20828 -0.08636) (xy 0.08636 -0.20828) (xy -0.08636 -0.20828)
					)
					(width 0)
					(fill yes)
				)
			)
		)
		(zone
			(layer "B.Cu")
			(hatch none 0.5)
			(connect_pads
				(clearance 0)
			)
			(min_thickness 0.25)
			(keepout
				(tracks not_allowed)
				(vias allowed)
				(pads allowed)
				(copperpour not_allowed)
				(footprints allowed)
			)
			(placement
				(enabled no)
				(sheetname "")
			)
			(fill
				(thermal_gap 0.5)
				(thermal_bridge_width 0.5)
				(island_removal_mode 0)
			)
			(polygon
				(pts
					(xy 375.632472 -77.684884) (xy 375.632472 -77.303884) (xy 375.457212 -77.303884) (xy 375.456958 -77.684884)
				)
			)
		)
		(zone
			(layer "B.Cu")
			(hatch none 0.5)
			(connect_pads
				(clearance 0)
			)
			(min_thickness 0.25)
			(keepout
				(tracks allowed)
				(vias not_allowed)
				(pads allowed)
				(copperpour not_allowed)
				(footprints allowed)
			)
			(placement
				(enabled no)
				(sheetname "")
			)
			(fill
				(thermal_gap 0.5)
				(thermal_bridge_width 0.5)
				(island_removal_mode 0)
			)
			(polygon
				(pts
					(xy 375.632472 -77.684884) (xy 375.632472 -77.303884) (xy 375.457212 -77.303884) (xy 375.456958 -77.684884)
				)
			)
		)
	)
	(footprint ""
		(layer "B.Cu")
		(at 327.914 -61.087 -90)
		(property "Reference" "R4R4"
			(at 0 0 90)
			(layer "B.SilkS")
			(hide yes)
			(effects
				(font
					(size 1.27 1.27)
				)
				(justify mirror)
			)
		)
		(property "Value" ""
			(at 0 0 90)
			(layer "B.Fab")
			(effects
				(font
					(size 1.27 1.27)
				)
				(justify mirror)
			)
		)
		(duplicate_pad_numbers_are_jumpers no)
		(fp_poly
			(pts
				(xy 0.2794 -0.1016) (xy -0.2794 -0.1016) (xy -0.2794 0.9906) (xy 0.2794 0.9906)
			)
			(stroke
				(width 0)
				(type default)
			)
			(fill no)
			(layer "B.CrtYd")
		)
		(fp_line
			(start -0.2794 0.9906)
			(end -0.2794 -0.1016)
			(stroke
				(width 0.1)
				(type default)
			)
			(layer "B.Fab")
		)
		(fp_line
			(start 0.2794 0.9906)
			(end -0.2794 0.9906)
			(stroke
				(width 0.1)
				(type default)
			)
			(layer "B.Fab")
		)
		(fp_line
			(start -0.2794 -0.1016)
			(end 0.2794 -0.1016)
			(stroke
				(width 0.1)
				(type default)
			)
			(layer "B.Fab")
		)
		(fp_line
			(start 0.2794 -0.1016)
			(end 0.2794 0.9906)
			(stroke
				(width 0.1)
				(type default)
			)
			(layer "B.Fab")
		)
		(pad "1" smd rect
			(at 0 0 90)
			(size 0.508 0.508)
			(layers "B.Cu" "B.Mask" "B.Paste")
			(net "PVCCIO_CPU0")
		)
		(pad "2" smd rect
			(at 0 0.889 90)
			(size 0.508 0.508)
			(layers "B.Cu" "B.Mask" "B.Paste")
			(net "H_CPU0_FAST_WAKE_N")
		)
		(zone
			(layer "B.Cu")
			(hatch none 0.5)
			(connect_pads
				(clearance 0)
			)
			(min_thickness 0.25)
			(keepout
				(tracks not_allowed)
				(vias allowed)
				(pads allowed)
				(copperpour not_allowed)
				(footprints allowed)
			)
			(placement
				(enabled no)
				(sheetname "")
			)
			(fill
				(thermal_gap 0.5)
				(thermal_bridge_width 0.5)
				(island_removal_mode 0)
			)
			(polygon
				(pts
					(xy 327.279 -60.833) (xy 327.279 -61.341) (xy 327.66 -61.341) (xy 327.66 -60.833)
				)
			)
		)
		(zone
			(layer "B.Cu")
			(hatch none 0.5)
			(connect_pads
				(clearance 0)
			)
			(min_thickness 0.25)
			(keepout
				(tracks allowed)
				(vias not_allowed)
				(pads allowed)
				(copperpour not_allowed)
				(footprints allowed)
			)
			(placement
				(enabled no)
				(sheetname "")
			)
			(fill
				(thermal_gap 0.5)
				(thermal_bridge_width 0.5)
				(island_removal_mode 0)
			)
			(polygon
				(pts
					(xy 327.66 -60.833) (xy 327.66 -61.341) (xy 327.279 -61.341) (xy 327.279 -60.833)
				)
			)
		)
	)
)
